(kicad_pcb
	(version 20260206)
	(generator "pcbnew")
	(generator_version "10.0")
	(general
		(thickness 1.6)
		(legacy_teardrops no)
	)
	(paper "A4")
	(title_block
		(title "timecard-production-celestica-r4006 — R4006-B0001-02_R01.brd")
		(comment 1 "Time Appliance Project (Time Card) / footprints 872-876 of 1113")
	)
	(layers
		(0 "F.Cu" signal "TOP")
		(4 "In1.Cu" signal "L02_GND1")
		(6 "In2.Cu" signal "L03_SIG1")
		(8 "In3.Cu" signal "L04_GND2")
		(10 "In4.Cu" signal "L05_VCC1")
		(12 "In5.Cu" signal "L06_VCC2")
		(14 "In6.Cu" signal "L07_GND3")
		(16 "In7.Cu" signal "L08_SIG2")
		(18 "In8.Cu" signal "L09_GND4")
		(2 "B.Cu" signal "BOTTOM")
		(9 "F.Adhes" user "F.Adhesive")
		(11 "B.Adhes" user "B.Adhesive")
		(13 "F.Paste" user "Package Geometry/Pastemask Top")
		(15 "B.Paste" user "Package Geometry/Pastemask Bottom")
		(5 "F.SilkS" user "Ref Des/Silkscreen Top")
		(7 "B.SilkS" user "Ref Des/Silkscreen Bottom")
		(1 "F.Mask" user "Board Geometry/Soldermask Top")
		(3 "B.Mask" user "Board Geometry/Soldermask Bottom")
		(17 "Dwgs.User" user "User.Drawings")
		(19 "Cmts.User" user "User.Comments")
		(21 "Eco1.User" user "User.Eco1")
		(23 "Eco2.User" user "User.Eco2")
		(25 "Edge.Cuts" user "Board Geometry/Outline")
		(27 "Margin" user)
		(31 "F.CrtYd" user "Package Geometry/Place Bound Top")
		(29 "B.CrtYd" user "Package Geometry/Place Bound Bottom")
		(35 "F.Fab" user "Ref Des/Assembly Top")
		(33 "B.Fab" user "Ref Des/Assembly Bottom")
	)
	(footprint ""
		(layer "B.Cu")
		(at 17.7292 -23.6728 90)
		(property "Reference" "R163"
			(at 1.3462 -1.13157 270)
			(unlocked yes)
			(layer "B.SilkS")
			(effects
				(font
					(size 0.7874 0.5842)
					(thickness 0.1524)
				)
				(justify mirror)
			)
		)
		(property "Value" "VAL*"
			(at -0.02032 2.13233 90)
			(unlocked yes)
			(layer "B.Fab")
			(hide yes)
			(effects
				(font
					(size 0.7874 0.5842)
					(thickness 0.1524)
				)
				(justify mirror)
			)
		)
		(property "Tolerance" "TOL*"
			(at -0.044704 3.05435 90)
			(unlocked yes)
			(layer "Cmts.User")
			(hide yes)
			(effects
				(font
					(size 0.7874 0.5842)
					(thickness 0.1524)
				)
				(justify mirror)
			)
		)
		(property "User Part Number" "PARTNUM*"
			(at -0.02032 4.024884 90)
			(unlocked yes)
			(layer "Cmts.User")
			(hide yes)
			(effects
				(font
					(size 0.7874 0.5842)
					(thickness 0.1524)
				)
				(justify mirror)
			)
		)
		(property "Device Type" "RESISTOR-G155-14701-01,4.7KOHMA"
			(at -0.008382 1.210564 90)
			(unlocked yes)
			(layer "B.Fab")
			(hide yes)
			(effects
				(font
					(size 0.7874 0.5842)
					(thickness 0.1524)
				)
				(justify mirror)
			)
		)
		(duplicate_pad_numbers_are_jumpers no)
		(fp_line
			(start 1.143 -0.5588)
			(end 1.143 0.5588)
			(stroke
				(width 0.1)
				(type default)
			)
			(layer "B.SilkS")
		)
		(fp_line
			(start -1.143 -0.5588)
			(end 1.143 -0.5588)
			(stroke
				(width 0.1)
				(type default)
			)
			(layer "B.SilkS")
		)
		(fp_line
			(start 1.143 0.5588)
			(end -1.143 0.5588)
			(stroke
				(width 0.1)
				(type default)
			)
			(layer "B.SilkS")
		)
		(fp_line
			(start -1.143 0.5588)
			(end -1.143 -0.5588)
			(stroke
				(width 0.1)
				(type default)
			)
			(layer "B.SilkS")
		)
		(fp_poly
			(pts
				(xy 1.143 0.5588) (xy -1.143 0.5588) (xy -1.143 -0.5588) (xy 1.143 -0.5588)
			)
			(stroke
				(width 0)
				(type default)
			)
			(fill no)
			(layer "B.CrtYd")
		)
		(fp_line
			(start 0.508 -0.3048)
			(end 0.508 0.3048)
			(stroke
				(width 0.1)
				(type default)
			)
			(layer "B.Fab")
		)
		(fp_line
			(start -0.508 -0.3048)
			(end 0.508 -0.3048)
			(stroke
				(width 0.1)
				(type default)
			)
			(layer "B.Fab")
		)
		(fp_line
			(start 0.508 0.3048)
			(end -0.508 0.3048)
			(stroke
				(width 0.1)
				(type default)
			)
			(layer "B.Fab")
		)
		(fp_line
			(start -0.508 0.3048)
			(end -0.508 -0.3048)
			(stroke
				(width 0.1)
				(type default)
			)
			(layer "B.Fab")
		)
		(pad "1" smd rect
			(at 0.5334 0 270)
			(size 0.7112 0.6096)
			(layers "B.Cu" "B.Mask" "B.Paste")
			(net "UNNAMED_5_24LC16BTISTTSSOP8_I_2")
		)
		(pad "2" smd rect
			(at -0.5334 0 270)
			(size 0.7112 0.6096)
			(layers "B.Cu" "B.Mask" "B.Paste")
			(net "SG")
		)
		(zone
			(layer "B.Cu")
			(hatch none 0.5)
			(connect_pads
				(clearance 0)
			)
			(min_thickness 0.25)
			(keepout
				(tracks allowed)
				(vias not_allowed)
				(pads allowed)
				(copperpour not_allowed)
				(footprints allowed)
			)
			(placement
				(enabled no)
				(sheetname "")
			)
			(fill
				(thermal_gap 0.5)
				(thermal_bridge_width 0.5)
				(island_removal_mode 0)
			)
			(polygon
				(pts
					(xy 18.034 -23.749) (xy 17.4244 -23.749) (xy 17.4244 -23.5966) (xy 18.034 -23.5966)
				)
			)
		)
		(zone
			(layer "B.Cu")
			(hatch none 0.5)
			(connect_pads
				(clearance 0)
			)
			(min_thickness 0.25)
			(keepout
				(tracks not_allowed)
				(vias allowed)
				(pads allowed)
				(copperpour not_allowed)
				(footprints allowed)
			)
			(placement
				(enabled no)
				(sheetname "")
			)
			(fill
				(thermal_gap 0.5)
				(thermal_bridge_width 0.5)
				(island_removal_mode 0)
			)
			(polygon
				(pts
					(xy 18.034 -23.749) (xy 17.4244 -23.749) (xy 17.4244 -23.5966) (xy 18.034 -23.5966)
				)
			)
		)
	)
	(footprint ""
		(layer "B.Cu")
		(at 107.347004 -45.823124)
		(property "Reference" "C200"
			(at -2.318004 0.261874 0)
			(unlocked yes)
			(layer "B.SilkS")
			(effects
				(font
					(size 0.635 0.4064)
					(thickness 0.1524)
				)
				(justify mirror)
			)
		)
		(property "Value" "VAL*"
			(at 0 3.718306 0)
			(unlocked yes)
			(layer "B.Fab")
			(hide yes)
			(effects
				(font
					(size 0.7874 0.5842)
					(thickness 0.127)
				)
				(justify mirror)
			)
		)
		(property "Tolerance" "TOL*"
			(at 0 4.861306 0)
			(unlocked yes)
			(layer "Cmts.User")
			(hide yes)
			(effects
				(font
					(size 0.7874 0.5842)
					(thickness 0.127)
				)
				(justify mirror)
			)
		)
		(property "User Part Number" "PARTNUM*"
			(at 0 2.575306 0)
			(unlocked yes)
			(layer "Cmts.User")
			(hide yes)
			(effects
				(font
					(size 0.7874 0.5842)
					(thickness 0.127)
				)
				(justify mirror)
			)
		)
		(property "Device Type" "CAPACITOR-G105-0B104-CK,0.1UF,A"
			(at 0 1.432306 0)
			(unlocked yes)
			(layer "B.Fab")
			(hide yes)
			(effects
				(font
					(size 0.7874 0.5842)
					(thickness 0.127)
				)
				(justify mirror)
			)
		)
		(duplicate_pad_numbers_are_jumpers no)
		(fp_line
			(start -0.970026 -0.4699)
			(end -0.970026 0.4699)
			(stroke
				(width 0.1)
				(type default)
			)
			(layer "B.SilkS")
		)
		(fp_line
			(start -0.970026 0.4699)
			(end 0.970026 0.4699)
			(stroke
				(width 0.1)
				(type default)
			)
			(layer "B.SilkS")
		)
		(fp_line
			(start 0.970026 -0.4699)
			(end -0.970026 -0.4699)
			(stroke
				(width 0.1)
				(type default)
			)
			(layer "B.SilkS")
		)
		(fp_line
			(start 0.970026 0.4699)
			(end 0.970026 -0.4699)
			(stroke
				(width 0.1)
				(type default)
			)
			(layer "B.SilkS")
		)
		(fp_poly
			(pts
				(xy 0.970026 0.4699) (xy -0.970026 0.4699) (xy -0.970026 -0.4699) (xy 0.970026 -0.4699)
			)
			(stroke
				(width 0)
				(type default)
			)
			(fill no)
			(layer "B.CrtYd")
		)
		(fp_line
			(start -0.508 -0.3048)
			(end -0.508 0.3048)
			(stroke
				(width 0.1)
				(type default)
			)
			(layer "B.Fab")
		)
		(fp_line
			(start -0.508 0.3048)
			(end 0.508 0.3048)
			(stroke
				(width 0.1)
				(type default)
			)
			(layer "B.Fab")
		)
		(fp_line
			(start 0.508 -0.3048)
			(end -0.508 -0.3048)
			(stroke
				(width 0.1)
				(type default)
			)
			(layer "B.Fab")
		)
		(fp_line
			(start 0.508 0.3048)
			(end 0.508 -0.3048)
			(stroke
				(width 0.1)
				(type default)
			)
			(layer "B.Fab")
		)
		(pad "1" smd circle
			(at 0.500126 0 180)
			(size 0.635 0.635)
			(layers "B.Cu" "B.Mask" "B.Paste")
			(net "XP1R8V_FPGA_VCCAUX")
		)
		(pad "2" smd circle
			(at -0.500126 0 180)
			(size 0.635 0.635)
			(layers "B.Cu" "B.Mask" "B.Paste")
			(net "SG")
		)
	)
	(footprint ""
		(layer "B.Cu")
		(at 34.417 -88.9 180)
		(property "Reference" "C96"
			(at -0.127 -1.18237 0)
			(unlocked yes)
			(layer "B.SilkS")
			(effects
				(font
					(size 0.7874 0.5842)
					(thickness 0.1524)
				)
				(justify mirror)
			)
		)
		(property "Value" "VAL*"
			(at -0.0762 2.067306 180)
			(unlocked yes)
			(layer "B.Fab")
			(hide yes)
			(effects
				(font
					(size 0.7874 0.5842)
					(thickness 0.1524)
				)
				(justify mirror)
			)
		)
		(property "Tolerance" "TOL*"
			(at -0.0762 3.032506 180)
			(unlocked yes)
			(layer "Cmts.User")
			(hide yes)
			(effects
				(font
					(size 0.7874 0.5842)
					(thickness 0.1524)
				)
				(justify mirror)
			)
		)
		(property "User Part Number" "PARTNUM*"
			(at -0.1016 4.023106 180)
			(unlocked yes)
			(layer "Cmts.User")
			(hide yes)
			(effects
				(font
					(size 0.7874 0.5842)
					(thickness 0.1524)
				)
				(justify mirror)
			)
		)
		(property "Device Type" "CAPACITOR-G105-0B104-EK,0.1UF,A"
			(at -0.0508 1.127506 180)
			(unlocked yes)
			(layer "B.Fab")
			(hide yes)
			(effects
				(font
					(size 0.7874 0.5842)
					(thickness 0.1524)
				)
				(justify mirror)
			)
		)
		(duplicate_pad_numbers_are_jumpers no)
		(fp_line
			(start 1.143 0.5588)
			(end -1.143 0.5588)
			(stroke
				(width 0.1)
				(type default)
			)
			(layer "B.SilkS")
		)
		(fp_line
			(start 1.143 -0.5588)
			(end 1.143 0.5588)
			(stroke
				(width 0.1)
				(type default)
			)
			(layer "B.SilkS")
		)
		(fp_line
			(start -1.143 0.5588)
			(end -1.143 -0.5588)
			(stroke
				(width 0.1)
				(type default)
			)
			(layer "B.SilkS")
		)
		(fp_line
			(start -1.143 -0.5588)
			(end 1.143 -0.5588)
			(stroke
				(width 0.1)
				(type default)
			)
			(layer "B.SilkS")
		)
		(fp_rect
			(start 1.143 0.5588)
			(end -1.143 -0.5588)
			(stroke
				(width 0)
				(type default)
			)
			(fill no)
			(layer "B.CrtYd")
		)
		(fp_line
			(start 0.508 0.3048)
			(end -0.508 0.3048)
			(stroke
				(width 0.1)
				(type default)
			)
			(layer "B.Fab")
		)
		(fp_line
			(start 0.508 -0.3048)
			(end 0.508 0.3048)
			(stroke
				(width 0.1)
				(type default)
			)
			(layer "B.Fab")
		)
		(fp_line
			(start -0.508 0.3048)
			(end -0.508 -0.3048)
			(stroke
				(width 0.1)
				(type default)
			)
			(layer "B.Fab")
		)
		(fp_line
			(start -0.508 -0.3048)
			(end 0.508 -0.3048)
			(stroke
				(width 0.1)
				(type default)
			)
			(layer "B.Fab")
		)
		(pad "1" smd rect
			(at 0.5334 0)
			(size 0.7112 0.6096)
			(layers "B.Cu" "B.Mask" "B.Paste")
			(net "FT4232_VREGOUT")
		)
		(pad "2" smd rect
			(at -0.5334 0)
			(size 0.7112 0.6096)
			(layers "B.Cu" "B.Mask" "B.Paste")
			(net "SG")
		)
		(zone
			(layer "B.Cu")
			(hatch none 0.5)
			(connect_pads
				(clearance 0)
			)
			(min_thickness 0.25)
			(keepout
				(tracks allowed)
				(vias not_allowed)
				(pads allowed)
				(copperpour not_allowed)
				(footprints allowed)
			)
			(placement
				(enabled no)
				(sheetname "")
			)
			(fill
				(thermal_gap 0.5)
				(thermal_bridge_width 0.5)
				(island_removal_mode 0)
			)
			(polygon
				(pts
					(xy 34.3408 -89.2048) (xy 34.3408 -88.5952) (xy 34.4932 -88.5952) (xy 34.4932 -89.2048)
				)
			)
		)
	)
	(footprint ""
		(layer "B.Cu")
		(at 135.0264 -91.6178 -90)
		(property "Reference" "CR3"
			(at -0.4826 2.98577 270)
			(unlocked yes)
			(layer "B.SilkS")
			(effects
				(font
					(size 0.7874 0.5842)
					(thickness 0.1524)
				)
				(justify mirror)
			)
		)
		(property "Value" "VAL*"
			(at -0.06985 6.435344 270)
			(unlocked yes)
			(layer "B.Fab")
			(hide yes)
			(effects
				(font
					(size 0.7874 0.5842)
					(thickness 0.1524)
				)
				(justify mirror)
			)
		)
		(property "User Part Number" "PARTNUM*"
			(at 0 4.531868 270)
			(unlocked yes)
			(layer "Cmts.User")
			(hide yes)
			(effects
				(font
					(size 0.7874 0.5842)
					(thickness 0.1524)
				)
				(justify mirror)
			)
		)
		(property "Device Type" "DIODE_2-G122-00005-01"
			(at 0 3.338068 270)
			(unlocked yes)
			(layer "B.Fab")
			(hide yes)
			(effects
				(font
					(size 0.7874 0.5842)
					(thickness 0.1524)
				)
				(justify mirror)
			)
		)
		(property "Tolerance" "TOL*"
			(at -0.031496 5.488178 270)
			(unlocked yes)
			(layer "Cmts.User")
			(hide yes)
			(effects
				(font
					(size 0.7874 0.5842)
					(thickness 0.1524)
				)
				(justify mirror)
			)
		)
		(duplicate_pad_numbers_are_jumpers no)
		(fp_line
			(start -3.543554 2.229104)
			(end 3.543554 2.229104)
			(stroke
				(width 0.1)
				(type default)
			)
			(layer "B.SilkS")
		)
		(fp_line
			(start 3.543554 2.229104)
			(end 3.543554 -2.229104)
			(stroke
				(width 0.1)
				(type default)
			)
			(layer "B.SilkS")
		)
		(fp_line
			(start 3.861562 -1.763014)
			(end 5.131562 -1.763014)
			(stroke
				(width 0.1)
				(type default)
			)
			(layer "B.SilkS")
		)
		(fp_line
			(start -3.543554 -2.229104)
			(end -3.543554 2.229104)
			(stroke
				(width 0.1)
				(type default)
			)
			(layer "B.SilkS")
		)
		(fp_line
			(start 3.543554 -2.229104)
			(end -3.543554 -2.229104)
			(stroke
				(width 0.1)
				(type default)
			)
			(layer "B.SilkS")
		)
		(fp_line
			(start 4.496562 -2.398014)
			(end 4.496562 -1.128014)
			(stroke
				(width 0.1)
				(type default)
			)
			(layer "B.SilkS")
		)
		(fp_rect
			(start -4.051554 -2.229104)
			(end -3.543554 2.229104)
			(stroke
				(width 0)
				(type default)
			)
			(fill yes)
			(layer "B.SilkS")
		)
		(fp_rect
			(start -4.051554 -2.483104)
			(end 3.797554 2.483104)
			(stroke
				(width 0)
				(type default)
			)
			(fill no)
			(layer "B.CrtYd")
		)
		(fp_line
			(start -2.29997 1.975104)
			(end -2.29997 -1.975104)
			(stroke
				(width 0.1)
				(type default)
			)
			(layer "B.Fab")
		)
		(fp_line
			(start 2.29997 1.975104)
			(end -2.29997 1.975104)
			(stroke
				(width 0.1)
				(type default)
			)
			(layer "B.Fab")
		)
		(fp_line
			(start 3.861308 -1.763268)
			(end 5.131308 -1.763268)
			(stroke
				(width 0.1)
				(type default)
			)
			(layer "B.Fab")
		)
		(fp_line
			(start -2.29997 -1.975104)
			(end 2.29997 -1.975104)
			(stroke
				(width 0.1)
				(type default)
			)
			(layer "B.Fab")
		)
		(fp_line
			(start 2.29997 -1.975104)
			(end 2.29997 1.975104)
			(stroke
				(width 0.1)
				(type default)
			)
			(layer "B.Fab")
		)
		(fp_line
			(start 4.496308 -2.398268)
			(end 4.496308 -1.128268)
			(stroke
				(width 0.1)
				(type default)
			)
			(layer "B.Fab")
		)
		(fp_rect
			(start -2.29997 -1.975104)
			(end -1.79197 1.975104)
			(stroke
				(width 0)
				(type default)
			)
			(fill yes)
			(layer "B.Fab")
		)
		(fp_text user "A"
			(at 4.66217 0.4064 0)
			(unlocked yes)
			(layer "B.SilkS")
			(effects
				(font
					(size 0.7874 0.5842)
					(thickness 0.1524)
				)
				(justify mirror)
			)
		)
		(fp_text user "C"
			(at -4.48183 -1.6256 0)
			(unlocked yes)
			(layer "B.SilkS")
			(effects
				(font
					(size 0.7874 0.5842)
					(thickness 0.1524)
				)
				(justify mirror)
			)
		)
		(fp_text user "A"
			(at 3.39217 0.4064 0)
			(unlocked yes)
			(layer "B.Fab")
			(effects
				(font
					(size 0.7874 0.5842)
					(thickness 0.1524)
				)
				(justify mirror)
			)
		)
		(fp_text user "C"
			(at -4.10083 0.0254 0)
			(unlocked yes)
			(layer "B.Fab")
			(effects
				(font
					(size 0.7874 0.5842)
					(thickness 0.1524)
				)
				(justify mirror)
			)
		)
		(pad "A" smd rect
			(at 2.210054 0 90)
			(size 2.159 2.7432)
			(layers "B.Cu" "B.Mask" "B.Paste")
			(net "SG")
		)
		(pad "C" smd rect
			(at -2.210054 0 90)
			(size 2.159 2.7432)
			(layers "B.Cu" "B.Mask" "B.Paste")
			(net "XP12R0V")
		)
	)
	(footprint ""
		(layer "B.Cu")
		(at 95.631 -84.455)
		(property "Reference" "R204"
			(at -0.254 -5.54863 0)
			(unlocked yes)
			(layer "B.SilkS")
			(effects
				(font
					(size 0.7874 0.5842)
					(thickness 0.1524)
				)
				(justify mirror)
			)
		)
		(property "Value" "VAL*"
			(at -0.02032 2.13233 0)
			(unlocked yes)
			(layer "B.Fab")
			(hide yes)
			(effects
				(font
					(size 0.7874 0.5842)
					(thickness 0.1524)
				)
				(justify mirror)
			)
		)
		(property "Tolerance" "TOL*"
			(at -0.044704 3.05435 0)
			(unlocked yes)
			(layer "Cmts.User")
			(hide yes)
			(effects
				(font
					(size 0.7874 0.5842)
					(thickness 0.1524)
				)
				(justify mirror)
			)
		)
		(property "User Part Number" "PARTNUM*"
			(at -0.02032 4.024884 0)
			(unlocked yes)
			(layer "Cmts.User")
			(hide yes)
			(effects
				(font
					(size 0.7874 0.5842)
					(thickness 0.1524)
				)
				(justify mirror)
			)
		)
		(property "Device Type" "RESISTOR-G155-133R0-01,33OHM,1%"
			(at -0.008382 1.210564 0)
			(unlocked yes)
			(layer "B.Fab")
			(hide yes)
			(effects
				(font
					(size 0.7874 0.5842)
					(thickness 0.1524)
				)
				(justify mirror)
			)
		)
		(duplicate_pad_numbers_are_jumpers no)
		(fp_line
			(start -1.143 -0.5588)
			(end 1.143 -0.5588)
			(stroke
				(width 0.1)
				(type default)
			)
			(layer "B.SilkS")
		)
		(fp_line
			(start -1.143 0.5588)
			(end -1.143 -0.5588)
			(stroke
				(width 0.1)
				(type default)
			)
			(layer "B.SilkS")
		)
		(fp_line
			(start 1.143 -0.5588)
			(end 1.143 0.5588)
			(stroke
				(width 0.1)
				(type default)
			)
			(layer "B.SilkS")
		)
		(fp_line
			(start 1.143 0.5588)
			(end -1.143 0.5588)
			(stroke
				(width 0.1)
				(type default)
			)
			(layer "B.SilkS")
		)
		(fp_rect
			(start -1.143 0.5588)
			(end 1.143 -0.5588)
			(stroke
				(width 0)
				(type default)
			)
			(fill no)
			(layer "B.CrtYd")
		)
		(fp_line
			(start -0.508 -0.3048)
			(end 0.508 -0.3048)
			(stroke
				(width 0.1)
				(type default)
			)
			(layer "B.Fab")
		)
		(fp_line
			(start -0.508 0.3048)
			(end -0.508 -0.3048)
			(stroke
				(width 0.1)
				(type default)
			)
			(layer "B.Fab")
		)
		(fp_line
			(start 0.508 -0.3048)
			(end 0.508 0.3048)
			(stroke
				(width 0.1)
				(type default)
			)
			(layer "B.Fab")
		)
		(fp_line
			(start 0.508 0.3048)
			(end -0.508 0.3048)
			(stroke
				(width 0.1)
				(type default)
			)
			(layer "B.Fab")
		)
		(pad "1" smd rect
			(at 0.5334 0 180)
			(size 0.7112 0.6096)
			(layers "B.Cu" "B.Mask" "B.Paste")
			(net "UNNAMED_127_MT25QL128ABA1ESES_1")
		)
		(pad "2" smd rect
			(at -0.5334 0 180)
			(size 0.7112 0.6096)
			(layers "B.Cu" "B.Mask" "B.Paste")
			(net "FLASH_DQ1_MISO")
		)
		(zone
			(layer "B.Cu")
			(hatch none 0.5)
			(connect_pads
				(clearance 0)
			)
			(min_thickness 0.25)
			(keepout
				(tracks allowed)
				(vias not_allowed)
				(pads allowed)
				(copperpour not_allowed)
				(footprints allowed)
			)
			(placement
				(enabled no)
				(sheetname "")
			)
			(fill
				(thermal_gap 0.5)
				(thermal_bridge_width 0.5)
				(island_removal_mode 0)
			)
			(polygon
				(pts
					(xy 95.5548 -84.1502) (xy 95.7072 -84.1502) (xy 95.7072 -84.7598) (xy 95.5548 -84.7598)
				)
			)
		)
	)
)
